# SCM (Grand Teton) — schematic netlist excerpt (pin names and nets, part order shuffled) for the footprints in the layout excerpt that follows; sources: Cadence DE-HDL packaged netlist, KiCad conversion of 12092022_DA0F0TMDCD0_F0T_Management_Board_D_brd_V3_OCP.brd

R801  Q_RES  33.2 1% CHIP  pkg 0402LF  page 13 : A = SPI_BMC_BOOT_CS0_R_N ; B = SPI_BMC_BOOT_CS0_R1_N
R204  Q_RES  10K 1% CHIP  pkg 0402LF  page 32 : A = P3V3_RGM ; B = JTAG_SCM_TDI

(kicad_pcb
	(version 20260206)
	(generator "pcbnew")
	(generator_version "10.0")
	(general
		(thickness 1.6)
		(legacy_teardrops no)
	)
	(paper "A4")
	(title_block
		(title "12092022_DA0F0TMDCD0_F0T_Management_Board_D_brd_V3_OCP.brd")
		(comment 1 "Grand Teton / footprints 877-878 of 1440")
	)
	(layers
		(0 "F.Cu" signal "TOP")
		(4 "In1.Cu" signal "GND")
		(6 "In2.Cu" signal "IN1")
		(8 "In3.Cu" signal "GND1")
		(10 "In4.Cu" signal "IN2")
		(12 "In5.Cu" signal "VCC")
		(14 "In6.Cu" signal "VCC1")
		(16 "In7.Cu" signal "IN3")
		(18 "In8.Cu" signal "GND2")
		(20 "In9.Cu" signal "IN4")
		(22 "In10.Cu" signal "GND3")
		(2 "B.Cu" signal "BOTTOM")
		(9 "F.Adhes" user "F.Adhesive")
		(11 "B.Adhes" user "B.Adhesive")
		(13 "F.Paste" user "Package Geometry/Pastemask Top")
		(15 "B.Paste" user "Package Geometry/Pastemask Bottom")
		(5 "F.SilkS" user "Ref Des/Silkscreen Top")
		(7 "B.SilkS" user "Ref Des/Silkscreen Bottom")
		(1 "F.Mask" user "Board Geometry/Soldermask Top")
		(3 "B.Mask" user "Board Geometry/Soldermask Bottom")
		(17 "Dwgs.User" user "User.Drawings")
		(19 "Cmts.User" user "User.Comments")
		(21 "Eco1.User" user "User.Eco1")
		(23 "Eco2.User" user "User.Eco2")
		(25 "Edge.Cuts" user "Board Geometry/Outline")
		(27 "Margin" user)
		(31 "F.CrtYd" user "Package Geometry/Place Bound Top")
		(29 "B.CrtYd" user "Package Geometry/Place Bound Bottom")
		(35 "F.Fab" user "Ref Des/Assembly Top")
		(33 "B.Fab" user "Ref Des/Assembly Bottom")
	)
	(footprint ""
		(layer "B.Cu")
		(at 56.710326 -60.8076 90)
		(property "Reference" "R801"
			(at 0 0 90)
			(layer "B.SilkS")
			(hide yes)
			(effects
				(font
					(size 1.27 1.27)
				)
				(justify mirror)
			)
		)
		(property "Value" ""
			(at 0 0 90)
			(layer "B.Fab")
			(effects
				(font
					(size 1.27 1.27)
				)
				(justify mirror)
			)
		)
		(duplicate_pad_numbers_are_jumpers no)
		(fp_line
			(start 0.7874 -0.4064)
			(end -0.7874 -0.4064)
			(stroke
				(width 0.1524)
				(type default)
			)
			(layer "B.SilkS")
		)
		(fp_line
			(start -0.7874 -0.4064)
			(end -0.7874 0.4064)
			(stroke
				(width 0.1524)
				(type default)
			)
			(layer "B.SilkS")
		)
		(fp_line
			(start 0.7874 0.4064)
			(end 0.7874 -0.4064)
			(stroke
				(width 0.1524)
				(type default)
			)
			(layer "B.SilkS")
		)
		(fp_line
			(start -0.7874 0.4064)
			(end 0.7874 0.4064)
			(stroke
				(width 0.1524)
				(type default)
			)
			(layer "B.SilkS")
		)
		(fp_line
			(start 0.67945 -0.305054)
			(end 0.12065 -0.305054)
			(stroke
				(width 0.1)
				(type default)
			)
			(layer "B.Fab")
		)
		(fp_line
			(start 0.12065 -0.305054)
			(end 0.12065 -0.2794)
			(stroke
				(width 0.1)
				(type default)
			)
			(layer "B.Fab")
		)
		(fp_line
			(start -0.12065 -0.3048)
			(end -0.67945 -0.3048)
			(stroke
				(width 0.1)
				(type default)
			)
			(layer "B.Fab")
		)
		(fp_line
			(start -0.67945 -0.3048)
			(end -0.67945 0.3048)
			(stroke
				(width 0.1)
				(type default)
			)
			(layer "B.Fab")
		)
		(fp_line
			(start 0.12065 -0.2794)
			(end -0.12065 -0.2794)
			(stroke
				(width 0.1)
				(type default)
			)
			(layer "B.Fab")
		)
		(fp_line
			(start -0.12065 -0.2794)
			(end -0.12065 -0.3048)
			(stroke
				(width 0.1)
				(type default)
			)
			(layer "B.Fab")
		)
		(fp_line
			(start 0.12065 0.2794)
			(end 0.12065 0.3048)
			(stroke
				(width 0.1)
				(type default)
			)
			(layer "B.Fab")
		)
		(fp_line
			(start -0.120396 0.2794)
			(end 0.12065 0.2794)
			(stroke
				(width 0.1)
				(type default)
			)
			(layer "B.Fab")
		)
		(fp_line
			(start 0.67945 0.3048)
			(end 0.67945 -0.305054)
			(stroke
				(width 0.1)
				(type default)
			)
			(layer "B.Fab")
		)
		(fp_line
			(start 0.12065 0.3048)
			(end 0.67945 0.3048)
			(stroke
				(width 0.1)
				(type default)
			)
			(layer "B.Fab")
		)
		(fp_line
			(start -0.120396 0.3048)
			(end -0.120396 0.2794)
			(stroke
				(width 0.1)
				(type default)
			)
			(layer "B.Fab")
		)
		(fp_line
			(start -0.67945 0.3048)
			(end -0.120396 0.3048)
			(stroke
				(width 0.1)
				(type default)
			)
			(layer "B.Fab")
		)
		(pad "1" smd circle
			(at 0.40005 0 270)
			(size 0 0)
			(layers "B.Cu" "B.Mask" "B.Paste")
			(net "SPI_BMC_BOOT_CS0_R_N")
		)
		(pad "2" smd circle
			(at -0.40005 0 270)
			(size 0 0)
			(layers "B.Cu" "B.Mask" "B.Paste")
			(net "SPI_BMC_BOOT_CS0_R1_N")
		)
	)
	(footprint ""
		(layer "B.Cu")
		(at 65.0494 -28.3464 90)
		(property "Reference" "R204"
			(at 0 0 90)
			(layer "B.SilkS")
			(hide yes)
			(effects
				(font
					(size 1.27 1.27)
				)
				(justify mirror)
			)
		)
		(property "Value" ""
			(at 0 0 90)
			(layer "B.Fab")
			(effects
				(font
					(size 1.27 1.27)
				)
				(justify mirror)
			)
		)
		(duplicate_pad_numbers_are_jumpers no)
		(fp_line
			(start 0.7874 -0.4064)
			(end -0.7874 -0.4064)
			(stroke
				(width 0.1524)
				(type default)
			)
			(layer "B.SilkS")
		)
		(fp_line
			(start -0.7874 -0.4064)
			(end -0.7874 0.4064)
			(stroke
				(width 0.1524)
				(type default)
			)
			(layer "B.SilkS")
		)
		(fp_line
			(start 0.7874 0.4064)
			(end 0.7874 -0.4064)
			(stroke
				(width 0.1524)
				(type default)
			)
			(layer "B.SilkS")
		)
		(fp_line
			(start -0.7874 0.4064)
			(end 0.7874 0.4064)
			(stroke
				(width 0.1524)
				(type default)
			)
			(layer "B.SilkS")
		)
		(fp_line
			(start 0.67945 -0.305054)
			(end 0.12065 -0.305054)
			(stroke
				(width 0.1)
				(type default)
			)
			(layer "B.Fab")
		)
		(fp_line
			(start 0.12065 -0.305054)
			(end 0.12065 -0.2794)
			(stroke
				(width 0.1)
				(type default)
			)
			(layer "B.Fab")
		)
		(fp_line
			(start -0.12065 -0.3048)
			(end -0.67945 -0.3048)
			(stroke
				(width 0.1)
				(type default)
			)
			(layer "B.Fab")
		)
		(fp_line
			(start -0.67945 -0.3048)
			(end -0.67945 0.3048)
			(stroke
				(width 0.1)
				(type default)
			)
			(layer "B.Fab")
		)
		(fp_line
			(start 0.12065 -0.2794)
			(end -0.12065 -0.2794)
			(stroke
				(width 0.1)
				(type default)
			)
			(layer "B.Fab")
		)
		(fp_line
			(start -0.12065 -0.2794)
			(end -0.12065 -0.3048)
			(stroke
				(width 0.1)
				(type default)
			)
			(layer "B.Fab")
		)
		(fp_line
			(start 0.12065 0.2794)
			(end 0.12065 0.3048)
			(stroke
				(width 0.1)
				(type default)
			)
			(layer "B.Fab")
		)
		(fp_line
			(start -0.120396 0.2794)
			(end 0.12065 0.2794)
			(stroke
				(width 0.1)
				(type default)
			)
			(layer "B.Fab")
		)
		(fp_line
			(start 0.67945 0.3048)
			(end 0.67945 -0.305054)
			(stroke
				(width 0.1)
				(type default)
			)
			(layer "B.Fab")
		)
		(fp_line
			(start 0.12065 0.3048)
			(end 0.67945 0.3048)
			(stroke
				(width 0.1)
				(type default)
			)
			(layer "B.Fab")
		)
		(fp_line
			(start -0.120396 0.3048)
			(end -0.120396 0.2794)
			(stroke
				(width 0.1)
				(type default)
			)
			(layer "B.Fab")
		)
		(fp_line
			(start -0.67945 0.3048)
			(end -0.120396 0.3048)
			(stroke
				(width 0.1)
				(type default)
			)
			(layer "B.Fab")
		)
		(pad "1" smd circle
			(at 0.40005 0 270)
			(size 0 0)
			(layers "B.Cu" "B.Mask" "B.Paste")
			(net "P3V3_RGM")
		)
		(pad "2" smd circle
			(at -0.40005 0 270)
			(size 0 0)
			(layers "B.Cu" "B.Mask" "B.Paste")
			(net "JTAG_SCM_TDI")
		)
	)
)
